(kicad_pcb
	(version 20260206)
	(generator "pcbnew")
	(generator_version "10.0")
	(general
		(thickness 1.6)
		(legacy_teardrops no)
	)
	(paper "A4")
	(title_block
		(title "panther-plus-userver — 13130-1b_20150205.brd")
		(comment 1 "Honey Badger (Wiwynn) / footprint 406 of 1509 (DIMM2), pads 184-190 of 210")
	)
	(layers
		(0 "F.Cu" signal "TOP")
		(4 "In1.Cu" signal "L2")
		(6 "In2.Cu" signal "L3")
		(8 "In3.Cu" signal "L4")
		(10 "In4.Cu" signal "L5")
		(12 "In5.Cu" signal "L6")
		(14 "In6.Cu" signal "L7")
		(16 "In7.Cu" signal "L8")
		(18 "In8.Cu" signal "L9")
		(20 "In9.Cu" signal "L10")
		(22 "In10.Cu" signal "L11")
		(2 "B.Cu" signal "BOTTOM")
		(9 "F.Adhes" user "F.Adhesive")
		(11 "B.Adhes" user "B.Adhesive")
		(13 "F.Paste" user "Package Geometry/Pastemask Top")
		(15 "B.Paste" user "Package Geometry/Pastemask Bottom")
		(5 "F.SilkS" user "Ref Des/Silkscreen Top")
		(7 "B.SilkS" user "Ref Des/Silkscreen Bottom")
		(1 "F.Mask" user "Board Geometry/Soldermask Top")
		(3 "B.Mask" user "Board Geometry/Soldermask Bottom")
		(17 "Dwgs.User" user "User.Drawings")
		(19 "Cmts.User" user "User.Comments")
		(21 "Eco1.User" user "User.Eco1")
		(23 "Eco2.User" user "User.Eco2")
		(25 "Edge.Cuts" user "Board Geometry/Outline")
		(27 "Margin" user)
		(31 "F.CrtYd" user "Package Geometry/Place Bound Top")
		(29 "B.CrtYd" user "Package Geometry/Place Bound Bottom")
		(35 "F.Fab" user "Ref Des/Assembly Top")
		(33 "B.Fab" user "Ref Des/Assembly Bottom")
	)
	(footprint ""
		(layer "F.Cu")
		(at 158.500064 -66.699892 180)
		(property "Reference" "DIMM2"
			(at 0 0 180)
			(layer "F.SilkS")
			(hide yes)
			(effects
				(font
					(size 1.27 1.27)
				)
			)
		)
		(property "Value" "DDR3-204P-174-COLAY-1-GP"
			(at -40.682164 -17.468088 180)
			(unlocked yes)
			(layer "F.Fab")
			(hide yes)
			(effects
				(font
					(size 1.016 1.016)
					(thickness 0.1524)
				)
			)
		)
		(property "Device Type" "AS0A626-H8SN-7H-COLAY-1"
			(at -40.682164 -18.992088 180)
			(unlocked yes)
			(layer "F.Fab")
			(hide yes)
			(effects
				(font
					(size 1.016 1.016)
					(thickness 0.1524)
				)
			)
		)
		(duplicate_pad_numbers_are_jumpers no)
		(pad "182" smd custom
			(at 25.049988 -4.106672 180)
			(size 0.1143 0.1143)
			(layers "F.Cu" "F.Mask" "F.Paste")
			(net "M_A_DQ57")
			(options
				(clearance outline)
				(anchor circle)
			)
			(primitives
				(gr_poly
					(pts
						(xy 0 0.9017) (xy -0.03175 0.89916) (xy -0.0635 0.889) (xy -0.09144 0.87376) (xy -0.11684 0.85344)
						(xy -0.13716 0.82804) (xy -0.1524 0.8001) (xy -0.16256 0.76835) (xy -0.1651 0.7366) (xy -0.1651 0.44958)
						(xy -0.17272 0.44196) (xy -0.19812 0.4064) (xy -0.2032 0.39624) (xy -0.20701 0.38735) (xy -0.21209 0.37719)
						(xy -0.2159 0.36703) (xy -0.21844 0.35687) (xy -0.22225 0.34544) (xy -0.22352 0.33528) (xy -0.22606 0.32512)
						(xy -0.22733 0.31369) (xy -0.22733 0.30353) (xy -0.2286 0.2921) (xy -0.22733 0.28067) (xy -0.22733 0.27051)
						(xy -0.22606 0.25908) (xy -0.22352 0.24892) (xy -0.22225 0.23876) (xy -0.21844 0.22733) (xy -0.2159 0.21717)
						(xy -0.21209 0.20701) (xy -0.20701 0.19685) (xy -0.2032 0.18796) (xy -0.19812 0.1778) (xy -0.17272 0.14224)
						(xy -0.1651 0.13462) (xy -0.1651 -0.7366) (xy -0.16256 -0.76835) (xy -0.1524 -0.8001) (xy -0.13716 -0.82804)
						(xy -0.11684 -0.85344) (xy -0.09144 -0.87376) (xy -0.0635 -0.889) (xy -0.03175 -0.89916) (xy 0 -0.9017)
						(xy 0.03175 -0.89916) (xy 0.0635 -0.889) (xy 0.09144 -0.87376) (xy 0.11684 -0.85344) (xy 0.13716 -0.82804)
						(xy 0.1524 -0.8001) (xy 0.16256 -0.76835) (xy 0.1651 -0.7366) (xy 0.1651 0.13462) (xy 0.17272 0.14224)
						(xy 0.19812 0.1778) (xy 0.2032 0.18796) (xy 0.20701 0.19685) (xy 0.21209 0.20701) (xy 0.2159 0.21717)
						(xy 0.21844 0.22733) (xy 0.22225 0.23876) (xy 0.22352 0.24892) (xy 0.22606 0.25908) (xy 0.22733 0.27051)
						(xy 0.22733 0.28067) (xy 0.2286 0.2921) (xy 0.22733 0.30353) (xy 0.22733 0.31369) (xy 0.22606 0.32512)
						(xy 0.22352 0.33528) (xy 0.22225 0.34544) (xy 0.21844 0.35687) (xy 0.2159 0.36703) (xy 0.21209 0.37719)
						(xy 0.20701 0.38735) (xy 0.2032 0.39624) (xy 0.19812 0.4064) (xy 0.17272 0.44196) (xy 0.1651 0.44958)
						(xy 0.1651 0.7366) (xy 0.16256 0.76835) (xy 0.1524 0.8001) (xy 0.13716 0.82804) (xy 0.11684 0.85344)
						(xy 0.09144 0.87376) (xy 0.0635 0.889) (xy 0.03175 0.89916)
					)
					(width 0)
					(fill yes)
				)
			)
		)
		(pad "183" smd custom
			(at 25.349962 4.106672 180)
			(size 0.1143 0.1143)
			(layers "F.Cu" "F.Mask" "F.Paste")
			(net "M_A_DQ60")
			(options
				(clearance outline)
				(anchor circle)
			)
			(primitives
				(gr_poly
					(pts
						(xy 0 0.9017) (xy -0.03175 0.89916) (xy -0.0635 0.889) (xy -0.09144 0.87376) (xy -0.11684 0.85344)
						(xy -0.13716 0.82804) (xy -0.1524 0.8001) (xy -0.16256 0.76835) (xy -0.1651 0.7366) (xy -0.1651 0.11938)
						(xy -0.17272 0.11176) (xy -0.19812 0.0762) (xy -0.2032 0.06604) (xy -0.20701 0.05715) (xy -0.21209 0.04699)
						(xy -0.2159 0.03683) (xy -0.21844 0.02667) (xy -0.22225 0.01524) (xy -0.22352 0.00508) (xy -0.22606 -0.00508)
						(xy -0.22733 -0.01651) (xy -0.22733 -0.02667) (xy -0.2286 -0.0381) (xy -0.22733 -0.04953) (xy -0.22733 -0.05969)
						(xy -0.22606 -0.07112) (xy -0.22352 -0.08128) (xy -0.22225 -0.09144) (xy -0.21844 -0.10287) (xy -0.2159 -0.11303)
						(xy -0.21209 -0.12319) (xy -0.20701 -0.13335) (xy -0.2032 -0.14224) (xy -0.19812 -0.1524) (xy -0.17272 -0.18796)
						(xy -0.1651 -0.19558) (xy -0.1651 -0.7366) (xy -0.16256 -0.76835) (xy -0.1524 -0.8001) (xy -0.13716 -0.82804)
						(xy -0.11684 -0.85344) (xy -0.09144 -0.87376) (xy -0.0635 -0.889) (xy -0.03175 -0.89916) (xy 0 -0.9017)
						(xy 0.03175 -0.89916) (xy 0.0635 -0.889) (xy 0.09144 -0.87376) (xy 0.11684 -0.85344) (xy 0.13716 -0.82804)
						(xy 0.1524 -0.8001) (xy 0.16256 -0.76835) (xy 0.1651 -0.7366) (xy 0.1651 -0.19685) (xy 0.17272 -0.18923)
						(xy 0.17907 -0.18034) (xy 0.18669 -0.17145) (xy 0.19177 -0.16256) (xy 0.19812 -0.15367) (xy 0.20828 -0.13335)
						(xy 0.21971 -0.10287) (xy 0.22225 -0.09271) (xy 0.22479 -0.08128) (xy 0.22606 -0.07112) (xy 0.2286 -0.05969)
						(xy 0.2286 -0.01651) (xy 0.22606 -0.00508) (xy 0.22479 0.00508) (xy 0.22225 0.01651) (xy 0.21971 0.02667)
						(xy 0.20828 0.05715) (xy 0.19812 0.07747) (xy 0.19177 0.08636) (xy 0.18669 0.09525) (xy 0.17907 0.10414)
						(xy 0.17272 0.11303) (xy 0.1651 0.12065) (xy 0.1651 0.7366) (xy 0.16256 0.76835) (xy 0.1524 0.8001)
						(xy 0.13716 0.82804) (xy 0.11684 0.85344) (xy 0.09144 0.87376) (xy 0.0635 0.889) (xy 0.03175 0.89916)
					)
					(width 0)
					(fill yes)
				)
			)
		)
		(pad "184" smd custom
			(at 25.649936 -4.106672 180)
			(size 0.1143 0.1143)
			(layers "F.Cu" "F.Mask" "F.Paste")
			(net "GND")
			(options
				(clearance outline)
				(anchor circle)
			)
			(primitives
				(gr_poly
					(pts
						(xy 0 0.9017) (xy -0.03175 0.89916) (xy -0.0635 0.889) (xy -0.09144 0.87376) (xy -0.11684 0.85344)
						(xy -0.13716 0.82804) (xy -0.1524 0.8001) (xy -0.16256 0.76835) (xy -0.1651 0.7366) (xy -0.1651 0.19685)
						(xy -0.17272 0.18923) (xy -0.17907 0.18034) (xy -0.18669 0.17145) (xy -0.19177 0.16256) (xy -0.19812 0.15367)
						(xy -0.20828 0.13335) (xy -0.21971 0.10287) (xy -0.22225 0.09271) (xy -0.22479 0.08128) (xy -0.22606 0.07112)
						(xy -0.2286 0.05969) (xy -0.2286 0.01651) (xy -0.22606 0.00508) (xy -0.22479 -0.00508) (xy -0.22225 -0.01651)
						(xy -0.21971 -0.02667) (xy -0.20828 -0.05715) (xy -0.19812 -0.07747) (xy -0.19177 -0.08636) (xy -0.18669 -0.09525)
						(xy -0.17907 -0.10414) (xy -0.17272 -0.11303) (xy -0.1651 -0.12065) (xy -0.1651 -0.7366) (xy -0.16256 -0.76835)
						(xy -0.1524 -0.8001) (xy -0.13716 -0.82804) (xy -0.11684 -0.85344) (xy -0.09144 -0.87376) (xy -0.0635 -0.889)
						(xy -0.03175 -0.89916) (xy 0 -0.9017) (xy 0.03175 -0.89916) (xy 0.0635 -0.889) (xy 0.09144 -0.87376)
						(xy 0.11684 -0.85344) (xy 0.13716 -0.82804) (xy 0.1524 -0.8001) (xy 0.16256 -0.76835) (xy 0.1651 -0.7366)
						(xy 0.1651 -0.11938) (xy 0.17272 -0.11176) (xy 0.19812 -0.0762) (xy 0.2032 -0.06604) (xy 0.20701 -0.05715)
						(xy 0.21209 -0.04699) (xy 0.2159 -0.03683) (xy 0.21844 -0.02667) (xy 0.22225 -0.01524) (xy 0.22352 -0.00508)
						(xy 0.22606 0.00508) (xy 0.22733 0.01651) (xy 0.22733 0.02667) (xy 0.2286 0.0381) (xy 0.22733 0.04953)
						(xy 0.22733 0.05969) (xy 0.22606 0.07112) (xy 0.22352 0.08128) (xy 0.22225 0.09144) (xy 0.21844 0.10287)
						(xy 0.2159 0.11303) (xy 0.21209 0.12319) (xy 0.20701 0.13335) (xy 0.2032 0.14224) (xy 0.19812 0.1524)
						(xy 0.17272 0.18796) (xy 0.1651 0.19558) (xy 0.1651 0.7366) (xy 0.16256 0.76835) (xy 0.1524 0.8001)
						(xy 0.13716 0.82804) (xy 0.11684 0.85344) (xy 0.09144 0.87376) (xy 0.0635 0.889) (xy 0.03175 0.89916)
					)
					(width 0)
					(fill yes)
				)
			)
		)
		(pad "185" smd custom
			(at 25.94991 4.106672 180)
			(size 0.1143 0.1143)
			(layers "F.Cu" "F.Mask" "F.Paste")
			(net "M_A_DQ61")
			(options
				(clearance outline)
				(anchor circle)
			)
			(primitives
				(gr_poly
					(pts
						(xy 0 0.9017) (xy -0.03175 0.89916) (xy -0.0635 0.889) (xy -0.09144 0.87376) (xy -0.11684 0.85344)
						(xy -0.13716 0.82804) (xy -0.1524 0.8001) (xy -0.16256 0.76835) (xy -0.1651 0.7366) (xy -0.1651 -0.13462)
						(xy -0.17272 -0.14224) (xy -0.19812 -0.1778) (xy -0.2032 -0.18796) (xy -0.20701 -0.19685) (xy -0.21209 -0.20701)
						(xy -0.2159 -0.21717) (xy -0.21844 -0.22733) (xy -0.22225 -0.23876) (xy -0.22352 -0.24892) (xy -0.22606 -0.25908)
						(xy -0.22733 -0.27051) (xy -0.22733 -0.28067) (xy -0.2286 -0.2921) (xy -0.22733 -0.30353) (xy -0.22733 -0.31369)
						(xy -0.22606 -0.32512) (xy -0.22352 -0.33528) (xy -0.22225 -0.34544) (xy -0.21844 -0.35687) (xy -0.2159 -0.36703)
						(xy -0.21209 -0.37719) (xy -0.20701 -0.38735) (xy -0.2032 -0.39624) (xy -0.19812 -0.4064) (xy -0.17272 -0.44196)
						(xy -0.1651 -0.44958) (xy -0.1651 -0.7366) (xy -0.16256 -0.76835) (xy -0.1524 -0.8001) (xy -0.13716 -0.82804)
						(xy -0.11684 -0.85344) (xy -0.09144 -0.87376) (xy -0.0635 -0.889) (xy -0.03175 -0.89916) (xy 0 -0.9017)
						(xy 0.03175 -0.89916) (xy 0.0635 -0.889) (xy 0.09144 -0.87376) (xy 0.11684 -0.85344) (xy 0.13716 -0.82804)
						(xy 0.1524 -0.8001) (xy 0.16256 -0.76835) (xy 0.1651 -0.7366) (xy 0.1651 -0.44958) (xy 0.17272 -0.44196)
						(xy 0.19812 -0.4064) (xy 0.2032 -0.39624) (xy 0.20701 -0.38735) (xy 0.21209 -0.37719) (xy 0.2159 -0.36703)
						(xy 0.21844 -0.35687) (xy 0.22225 -0.34544) (xy 0.22352 -0.33528) (xy 0.22606 -0.32512) (xy 0.22733 -0.31369)
						(xy 0.22733 -0.30353) (xy 0.2286 -0.2921) (xy 0.22733 -0.28067) (xy 0.22733 -0.27051) (xy 0.22606 -0.25908)
						(xy 0.22352 -0.24892) (xy 0.22225 -0.23876) (xy 0.21844 -0.22733) (xy 0.2159 -0.21717) (xy 0.21209 -0.20701)
						(xy 0.20701 -0.19685) (xy 0.2032 -0.18796) (xy 0.19812 -0.1778) (xy 0.17272 -0.14224) (xy 0.1651 -0.13462)
						(xy 0.1651 0.7366) (xy 0.16256 0.76835) (xy 0.1524 0.8001) (xy 0.13716 0.82804) (xy 0.11684 0.85344)
						(xy 0.09144 0.87376) (xy 0.0635 0.889) (xy 0.03175 0.89916)
					)
					(width 0)
					(fill yes)
				)
			)
		)
		(pad "186" smd custom
			(at 26.249884 -4.106672 180)
			(size 0.1143 0.1143)
			(layers "F.Cu" "F.Mask" "F.Paste")
			(net "M_A_DQS_DN7")
			(options
				(clearance outline)
				(anchor circle)
			)
			(primitives
				(gr_poly
					(pts
						(xy 0 0.9017) (xy -0.03175 0.89916) (xy -0.0635 0.889) (xy -0.09144 0.87376) (xy -0.11684 0.85344)
						(xy -0.13716 0.82804) (xy -0.1524 0.8001) (xy -0.16256 0.76835) (xy -0.1651 0.7366) (xy -0.1651 0.44958)
						(xy -0.17272 0.44196) (xy -0.19812 0.4064) (xy -0.2032 0.39624) (xy -0.20701 0.38735) (xy -0.21209 0.37719)
						(xy -0.2159 0.36703) (xy -0.21844 0.35687) (xy -0.22225 0.34544) (xy -0.22352 0.33528) (xy -0.22606 0.32512)
						(xy -0.22733 0.31369) (xy -0.22733 0.30353) (xy -0.2286 0.2921) (xy -0.22733 0.28067) (xy -0.22733 0.27051)
						(xy -0.22606 0.25908) (xy -0.22352 0.24892) (xy -0.22225 0.23876) (xy -0.21844 0.22733) (xy -0.2159 0.21717)
						(xy -0.21209 0.20701) (xy -0.20701 0.19685) (xy -0.2032 0.18796) (xy -0.19812 0.1778) (xy -0.17272 0.14224)
						(xy -0.1651 0.13462) (xy -0.1651 -0.7366) (xy -0.16256 -0.76835) (xy -0.1524 -0.8001) (xy -0.13716 -0.82804)
						(xy -0.11684 -0.85344) (xy -0.09144 -0.87376) (xy -0.0635 -0.889) (xy -0.03175 -0.89916) (xy 0 -0.9017)
						(xy 0.03175 -0.89916) (xy 0.0635 -0.889) (xy 0.09144 -0.87376) (xy 0.11684 -0.85344) (xy 0.13716 -0.82804)
						(xy 0.1524 -0.8001) (xy 0.16256 -0.76835) (xy 0.1651 -0.7366) (xy 0.1651 0.13462) (xy 0.17272 0.14224)
						(xy 0.19812 0.1778) (xy 0.2032 0.18796) (xy 0.20701 0.19685) (xy 0.21209 0.20701) (xy 0.2159 0.21717)
						(xy 0.21844 0.22733) (xy 0.22225 0.23876) (xy 0.22352 0.24892) (xy 0.22606 0.25908) (xy 0.22733 0.27051)
						(xy 0.22733 0.28067) (xy 0.2286 0.2921) (xy 0.22733 0.30353) (xy 0.22733 0.31369) (xy 0.22606 0.32512)
						(xy 0.22352 0.33528) (xy 0.22225 0.34544) (xy 0.21844 0.35687) (xy 0.2159 0.36703) (xy 0.21209 0.37719)
						(xy 0.20701 0.38735) (xy 0.2032 0.39624) (xy 0.19812 0.4064) (xy 0.17272 0.44196) (xy 0.1651 0.44958)
						(xy 0.1651 0.7366) (xy 0.16256 0.76835) (xy 0.1524 0.8001) (xy 0.13716 0.82804) (xy 0.11684 0.85344)
						(xy 0.09144 0.87376) (xy 0.0635 0.889) (xy 0.03175 0.89916)
					)
					(width 0)
					(fill yes)
				)
			)
		)
		(pad "187" smd custom
			(at 26.550112 4.106672 180)
			(size 0.1143 0.1143)
			(layers "F.Cu" "F.Mask" "F.Paste")
			(net "GND")
			(options
				(clearance outline)
				(anchor circle)
			)
			(primitives
				(gr_poly
					(pts
						(xy 0 0.9017) (xy -0.03175 0.89916) (xy -0.0635 0.889) (xy -0.09144 0.87376) (xy -0.11684 0.85344)
						(xy -0.13716 0.82804) (xy -0.1524 0.8001) (xy -0.16256 0.76835) (xy -0.1651 0.7366) (xy -0.1651 0.11938)
						(xy -0.17272 0.11176) (xy -0.19812 0.0762) (xy -0.2032 0.06604) (xy -0.20701 0.05715) (xy -0.21209 0.04699)
						(xy -0.2159 0.03683) (xy -0.21844 0.02667) (xy -0.22225 0.01524) (xy -0.22352 0.00508) (xy -0.22606 -0.00508)
						(xy -0.22733 -0.01651) (xy -0.22733 -0.02667) (xy -0.2286 -0.0381) (xy -0.22733 -0.04953) (xy -0.22733 -0.05969)
						(xy -0.22606 -0.07112) (xy -0.22352 -0.08128) (xy -0.22225 -0.09144) (xy -0.21844 -0.10287) (xy -0.2159 -0.11303)
						(xy -0.21209 -0.12319) (xy -0.20701 -0.13335) (xy -0.2032 -0.14224) (xy -0.19812 -0.1524) (xy -0.17272 -0.18796)
						(xy -0.1651 -0.19558) (xy -0.1651 -0.7366) (xy -0.16256 -0.76835) (xy -0.1524 -0.8001) (xy -0.13716 -0.82804)
						(xy -0.11684 -0.85344) (xy -0.09144 -0.87376) (xy -0.0635 -0.889) (xy -0.03175 -0.89916) (xy 0 -0.9017)
						(xy 0.03175 -0.89916) (xy 0.0635 -0.889) (xy 0.09144 -0.87376) (xy 0.11684 -0.85344) (xy 0.13716 -0.82804)
						(xy 0.1524 -0.8001) (xy 0.16256 -0.76835) (xy 0.1651 -0.7366) (xy 0.1651 -0.19685) (xy 0.17272 -0.18923)
						(xy 0.17907 -0.18034) (xy 0.18669 -0.17145) (xy 0.19177 -0.16256) (xy 0.19812 -0.15367) (xy 0.20828 -0.13335)
						(xy 0.21971 -0.10287) (xy 0.22225 -0.09271) (xy 0.22479 -0.08128) (xy 0.22606 -0.07112) (xy 0.2286 -0.05969)
						(xy 0.2286 -0.01651) (xy 0.22606 -0.00508) (xy 0.22479 0.00508) (xy 0.22225 0.01651) (xy 0.21971 0.02667)
						(xy 0.20828 0.05715) (xy 0.19812 0.07747) (xy 0.19177 0.08636) (xy 0.18669 0.09525) (xy 0.17907 0.10414)
						(xy 0.17272 0.11303) (xy 0.1651 0.12065) (xy 0.1651 0.7366) (xy 0.16256 0.76835) (xy 0.1524 0.8001)
						(xy 0.13716 0.82804) (xy 0.11684 0.85344) (xy 0.09144 0.87376) (xy 0.0635 0.889) (xy 0.03175 0.89916)
					)
					(width 0)
					(fill yes)
				)
			)
		)
		(pad "188" smd custom
			(at 26.850086 -4.106672 180)
			(size 0.1143 0.1143)
			(layers "F.Cu" "F.Mask" "F.Paste")
			(net "M_A_DQS_DP7")
			(options
				(clearance outline)
				(anchor circle)
			)
			(primitives
				(gr_poly
					(pts
						(xy 0 0.9017) (xy -0.03175 0.89916) (xy -0.0635 0.889) (xy -0.09144 0.87376) (xy -0.11684 0.85344)
						(xy -0.13716 0.82804) (xy -0.1524 0.8001) (xy -0.16256 0.76835) (xy -0.1651 0.7366) (xy -0.1651 0.19685)
						(xy -0.17272 0.18923) (xy -0.17907 0.18034) (xy -0.18669 0.17145) (xy -0.19177 0.16256) (xy -0.19812 0.15367)
						(xy -0.20828 0.13335) (xy -0.21971 0.10287) (xy -0.22225 0.09271) (xy -0.22479 0.08128) (xy -0.22606 0.07112)
						(xy -0.2286 0.05969) (xy -0.2286 0.01651) (xy -0.22606 0.00508) (xy -0.22479 -0.00508) (xy -0.22225 -0.01651)
						(xy -0.21971 -0.02667) (xy -0.20828 -0.05715) (xy -0.19812 -0.07747) (xy -0.19177 -0.08636) (xy -0.18669 -0.09525)
						(xy -0.17907 -0.10414) (xy -0.17272 -0.11303) (xy -0.1651 -0.12065) (xy -0.1651 -0.7366) (xy -0.16256 -0.76835)
						(xy -0.1524 -0.8001) (xy -0.13716 -0.82804) (xy -0.11684 -0.85344) (xy -0.09144 -0.87376) (xy -0.0635 -0.889)
						(xy -0.03175 -0.89916) (xy 0 -0.9017) (xy 0.03175 -0.89916) (xy 0.0635 -0.889) (xy 0.09144 -0.87376)
						(xy 0.11684 -0.85344) (xy 0.13716 -0.82804) (xy 0.1524 -0.8001) (xy 0.16256 -0.76835) (xy 0.1651 -0.7366)
						(xy 0.1651 -0.11938) (xy 0.17272 -0.11176) (xy 0.19812 -0.0762) (xy 0.2032 -0.06604) (xy 0.20701 -0.05715)
						(xy 0.21209 -0.04699) (xy 0.2159 -0.03683) (xy 0.21844 -0.02667) (xy 0.22225 -0.01524) (xy 0.22352 -0.00508)
						(xy 0.22606 0.00508) (xy 0.22733 0.01651) (xy 0.22733 0.02667) (xy 0.2286 0.0381) (xy 0.22733 0.04953)
						(xy 0.22733 0.05969) (xy 0.22606 0.07112) (xy 0.22352 0.08128) (xy 0.22225 0.09144) (xy 0.21844 0.10287)
						(xy 0.2159 0.11303) (xy 0.21209 0.12319) (xy 0.20701 0.13335) (xy 0.2032 0.14224) (xy 0.19812 0.1524)
						(xy 0.17272 0.18796) (xy 0.1651 0.19558) (xy 0.1651 0.7366) (xy 0.16256 0.76835) (xy 0.1524 0.8001)
						(xy 0.13716 0.82804) (xy 0.11684 0.85344) (xy 0.09144 0.87376) (xy 0.0635 0.889) (xy 0.03175 0.89916)
					)
					(width 0)
					(fill yes)
				)
			)
		)
	)
)
